# T6G (Grand Teton) — schematic netlist excerpt (pin names and nets, part order shuffled) for the footprints in the layout excerpt that follows; sources: Cadence DE-HDL packaged netlist, KiCad conversion of 04192023_DAF0TMB3IC0_F0TG_MB_C_brd_V02_OCP.brd

C380  Q_CAP  0.1UF 10V 10% X7S  pkg C0201  page 345 : A = P1V8_CPU1_RT2_1A ; B = GND
C3925  Q_CAP  22UF 4V 20% X6S  pkg C0402  page 70 : A = PVDDCR_SOC_P0 ; B = GND
C2220  Q_CAP  22UF 4V 20% X6S  pkg C0402  page 69 : A = PVDDCR_CPU1_P0 ; B = GND

(kicad_pcb
	(version 20260206)
	(generator "pcbnew")
	(generator_version "10.0")
	(general
		(thickness 1.6)
		(legacy_teardrops no)
	)
	(paper "A4")
	(title_block
		(title "04192023_DAF0TMB3IC0_F0TG_MB_C_brd_V02_OCP.brd")
		(comment 1 "Grand Teton / footprints 6667-6669 of 8354")
	)
	(layers
		(0 "F.Cu" signal "TOP")
		(4 "In1.Cu" signal "GND")
		(6 "In2.Cu" signal "IN1")
		(8 "In3.Cu" signal "GND1")
		(10 "In4.Cu" signal "IN2")
		(12 "In5.Cu" signal "GND2")
		(14 "In6.Cu" signal "IN3")
		(16 "In7.Cu" signal "GND3")
		(18 "In8.Cu" signal "VCC")
		(20 "In9.Cu" signal "VCC1")
		(22 "In10.Cu" signal "GND4")
		(24 "In11.Cu" signal "IN4")
		(26 "In12.Cu" signal "GND5")
		(28 "In13.Cu" signal "IN5")
		(30 "In14.Cu" signal "GND6")
		(32 "In15.Cu" signal "IN6")
		(34 "In16.Cu" signal "GND7")
		(2 "B.Cu" signal "BOTTOM")
		(9 "F.Adhes" user "F.Adhesive")
		(11 "B.Adhes" user "B.Adhesive")
		(13 "F.Paste" user "Package Geometry/Pastemask Top")
		(15 "B.Paste" user "Package Geometry/Pastemask Bottom")
		(5 "F.SilkS" user "Ref Des/Silkscreen Top")
		(7 "B.SilkS" user "Ref Des/Silkscreen Bottom")
		(1 "F.Mask" user "Board Geometry/Soldermask Top")
		(3 "B.Mask" user "Board Geometry/Soldermask Bottom")
		(17 "Dwgs.User" user "User.Drawings")
		(19 "Cmts.User" user "User.Comments")
		(21 "Eco1.User" user "User.Eco1")
		(23 "Eco2.User" user "User.Eco2")
		(25 "Edge.Cuts" user "Board Geometry/Outline")
		(27 "Margin" user)
		(31 "F.CrtYd" user "Package Geometry/Place Bound Top")
		(29 "B.CrtYd" user "Package Geometry/Place Bound Bottom")
		(35 "F.Fab" user "Ref Des/Assembly Top")
		(33 "B.Fab" user "Ref Des/Assembly Bottom")
	)
	(footprint ""
		(layer "B.Cu")
		(at 359.416096 -256.012188 -90)
		(property "Reference" "C3925"
			(at 0 0 90)
			(layer "B.SilkS")
			(hide yes)
			(effects
				(font
					(size 1.27 1.27)
				)
				(justify mirror)
			)
		)
		(property "Value" ""
			(at 0 0 90)
			(layer "B.Fab")
			(effects
				(font
					(size 1.27 1.27)
				)
				(justify mirror)
			)
		)
		(duplicate_pad_numbers_are_jumpers no)
		(fp_line
			(start -0.7874 0.4064)
			(end 0.7874 0.4064)
			(stroke
				(width 0.1524)
				(type default)
			)
			(layer "B.SilkS")
		)
		(fp_line
			(start 0.7874 0.4064)
			(end 0.7874 -0.4064)
			(stroke
				(width 0.1524)
				(type default)
			)
			(layer "B.SilkS")
		)
		(fp_line
			(start -0.7874 -0.4064)
			(end -0.7874 0.4064)
			(stroke
				(width 0.1524)
				(type default)
			)
			(layer "B.SilkS")
		)
		(fp_line
			(start 0.7874 -0.4064)
			(end -0.7874 -0.4064)
			(stroke
				(width 0.1524)
				(type default)
			)
			(layer "B.SilkS")
		)
		(fp_line
			(start -0.67945 0.3048)
			(end -0.120396 0.3048)
			(stroke
				(width 0.1)
				(type default)
			)
			(layer "B.Fab")
		)
		(fp_line
			(start -0.120396 0.3048)
			(end -0.120396 0.2794)
			(stroke
				(width 0.1)
				(type default)
			)
			(layer "B.Fab")
		)
		(fp_line
			(start 0.12065 0.3048)
			(end 0.67945 0.3048)
			(stroke
				(width 0.1)
				(type default)
			)
			(layer "B.Fab")
		)
		(fp_line
			(start 0.67945 0.3048)
			(end 0.67945 -0.305054)
			(stroke
				(width 0.1)
				(type default)
			)
			(layer "B.Fab")
		)
		(fp_line
			(start -0.120396 0.2794)
			(end 0.12065 0.2794)
			(stroke
				(width 0.1)
				(type default)
			)
			(layer "B.Fab")
		)
		(fp_line
			(start 0.12065 0.2794)
			(end 0.12065 0.3048)
			(stroke
				(width 0.1)
				(type default)
			)
			(layer "B.Fab")
		)
		(fp_line
			(start -0.12065 -0.2794)
			(end -0.12065 -0.3048)
			(stroke
				(width 0.1)
				(type default)
			)
			(layer "B.Fab")
		)
		(fp_line
			(start 0.12065 -0.2794)
			(end -0.12065 -0.2794)
			(stroke
				(width 0.1)
				(type default)
			)
			(layer "B.Fab")
		)
		(fp_line
			(start -0.67945 -0.3048)
			(end -0.67945 0.3048)
			(stroke
				(width 0.1)
				(type default)
			)
			(layer "B.Fab")
		)
		(fp_line
			(start -0.12065 -0.3048)
			(end -0.67945 -0.3048)
			(stroke
				(width 0.1)
				(type default)
			)
			(layer "B.Fab")
		)
		(fp_line
			(start 0.12065 -0.305054)
			(end 0.12065 -0.2794)
			(stroke
				(width 0.1)
				(type default)
			)
			(layer "B.Fab")
		)
		(fp_line
			(start 0.67945 -0.305054)
			(end 0.12065 -0.305054)
			(stroke
				(width 0.1)
				(type default)
			)
			(layer "B.Fab")
		)
		(pad "1" smd circle
			(at 0.40005 0 90)
			(size 0 0)
			(layers "B.Cu" "B.Mask" "B.Paste")
			(net "PVDDCR_SOC_P0")
		)
		(pad "2" smd circle
			(at -0.40005 0 90)
			(size 0 0)
			(layers "B.Cu" "B.Mask" "B.Paste")
			(net "GND")
		)
	)
	(footprint ""
		(layer "B.Cu")
		(at 352.120454 -268.41831)
		(property "Reference" "C2220"
			(at 0 0 0)
			(layer "B.SilkS")
			(hide yes)
			(effects
				(font
					(size 1.27 1.27)
				)
				(justify mirror)
			)
		)
		(property "Value" ""
			(at 0 0 0)
			(layer "B.Fab")
			(effects
				(font
					(size 1.27 1.27)
				)
				(justify mirror)
			)
		)
		(duplicate_pad_numbers_are_jumpers no)
		(fp_line
			(start -0.7874 -0.4064)
			(end -0.7874 0.4064)
			(stroke
				(width 0.1524)
				(type default)
			)
			(layer "B.SilkS")
		)
		(fp_line
			(start -0.7874 0.4064)
			(end 0.7874 0.4064)
			(stroke
				(width 0.1524)
				(type default)
			)
			(layer "B.SilkS")
		)
		(fp_line
			(start 0.7874 -0.4064)
			(end -0.7874 -0.4064)
			(stroke
				(width 0.1524)
				(type default)
			)
			(layer "B.SilkS")
		)
		(fp_line
			(start 0.7874 0.4064)
			(end 0.7874 -0.4064)
			(stroke
				(width 0.1524)
				(type default)
			)
			(layer "B.SilkS")
		)
		(fp_line
			(start -0.67945 -0.3048)
			(end -0.67945 0.3048)
			(stroke
				(width 0.1)
				(type default)
			)
			(layer "B.Fab")
		)
		(fp_line
			(start -0.67945 0.3048)
			(end -0.120396 0.3048)
			(stroke
				(width 0.1)
				(type default)
			)
			(layer "B.Fab")
		)
		(fp_line
			(start -0.12065 -0.3048)
			(end -0.67945 -0.3048)
			(stroke
				(width 0.1)
				(type default)
			)
			(layer "B.Fab")
		)
		(fp_line
			(start -0.12065 -0.2794)
			(end -0.12065 -0.3048)
			(stroke
				(width 0.1)
				(type default)
			)
			(layer "B.Fab")
		)
		(fp_line
			(start -0.120396 0.2794)
			(end 0.12065 0.2794)
			(stroke
				(width 0.1)
				(type default)
			)
			(layer "B.Fab")
		)
		(fp_line
			(start -0.120396 0.3048)
			(end -0.120396 0.2794)
			(stroke
				(width 0.1)
				(type default)
			)
			(layer "B.Fab")
		)
		(fp_line
			(start 0.12065 -0.305054)
			(end 0.12065 -0.2794)
			(stroke
				(width 0.1)
				(type default)
			)
			(layer "B.Fab")
		)
		(fp_line
			(start 0.12065 -0.2794)
			(end -0.12065 -0.2794)
			(stroke
				(width 0.1)
				(type default)
			)
			(layer "B.Fab")
		)
		(fp_line
			(start 0.12065 0.2794)
			(end 0.12065 0.3048)
			(stroke
				(width 0.1)
				(type default)
			)
			(layer "B.Fab")
		)
		(fp_line
			(start 0.12065 0.3048)
			(end 0.67945 0.3048)
			(stroke
				(width 0.1)
				(type default)
			)
			(layer "B.Fab")
		)
		(fp_line
			(start 0.67945 -0.305054)
			(end 0.12065 -0.305054)
			(stroke
				(width 0.1)
				(type default)
			)
			(layer "B.Fab")
		)
		(fp_line
			(start 0.67945 0.3048)
			(end 0.67945 -0.305054)
			(stroke
				(width 0.1)
				(type default)
			)
			(layer "B.Fab")
		)
		(pad "1" smd circle
			(at 0.40005 0 180)
			(size 0 0)
			(layers "B.Cu" "B.Mask" "B.Paste")
			(net "PVDDCR_CPU1_P0")
		)
		(pad "2" smd circle
			(at -0.40005 0 180)
			(size 0 0)
			(layers "B.Cu" "B.Mask" "B.Paste")
			(net "GND")
		)
	)
	(footprint ""
		(layer "B.Cu")
		(at 156.60624 -386.766562 90)
		(property "Reference" "C380"
			(at 0 0 90)
			(layer "B.SilkS")
			(hide yes)
			(effects
				(font
					(size 1.27 1.27)
				)
				(justify mirror)
			)
		)
		(property "Value" ""
			(at 0 0 90)
			(layer "B.Fab")
			(effects
				(font
					(size 1.27 1.27)
				)
				(justify mirror)
			)
		)
		(duplicate_pad_numbers_are_jumpers no)
		(fp_line
			(start 0.299974 -0.150114)
			(end -0.299974 -0.150114)
			(stroke
				(width 0.1)
				(type default)
			)
			(layer "B.Fab")
		)
		(fp_line
			(start -0.299974 -0.150114)
			(end -0.299974 0.150114)
			(stroke
				(width 0.1)
				(type default)
			)
			(layer "B.Fab")
		)
		(fp_line
			(start 0.299974 0.150114)
			(end 0.299974 -0.150114)
			(stroke
				(width 0.1)
				(type default)
			)
			(layer "B.Fab")
		)
		(fp_line
			(start -0.299974 0.150114)
			(end 0.299974 0.150114)
			(stroke
				(width 0.1)
				(type default)
			)
			(layer "B.Fab")
		)
		(pad "1" smd rect
			(at 0.2667 0 270)
			(size 0.3048 0.381)
			(layers "B.Cu" "B.Mask" "B.Paste")
			(net "P1V8_CPU1_RT2_1A")
		)
		(pad "2" smd rect
			(at -0.2667 0 270)
			(size 0.3048 0.381)
			(layers "B.Cu" "B.Mask" "B.Paste")
			(net "GND")
		)
	)
)
